FILE_TYPE = CONNECTIVITY;
{Allegro Design Entry HDL 16.6-p007 (v16-6-112F) 10/10/2012}
"PAGE_NUMBER" = 190;
0"NC";
1"GND\g";
2"FM_CPU0_PKGID0";
3"FM_OC0_USB_N";
4"FM_CPU0_SKTOCC_LVT3_N";
5"FM_GLOBAL_RST_WARN_N";
6"RST_CPU1_LVC3_N";
7"CLK_32K_SUSCLK_PLD";
8"TP_CPLD1_PB16A_PCLKT2_1";
9"TP_CPLD1_PL1A_L_GPLLT_FB";
10"FM_UARTSW_MSB_N";
11"FM_CPU0_PROC_ID0";
12"RST_PCIE_PCH_PERST_N";
13"FM_PWR_BTN_R2_N";
14"RST_CPU1_LVC3_R1_N";
15"FM_PWR_BTN_N";
16"PU_RST_PERST_BIT0";
17"TP_CPLD1_PL2B_L_GPLLC_IN";
18"RST_PCIE_CPU_DEV1_N";
19"FM_MEM_EVENT_FUNC";
20"FM_DEBUG_RST_BTN_N";
21"RST_RSMRST_R_N";
22"FM_CPU_CATERR_DLY_LVT3_N";
23"FM_PCH_PLD_DATA";
24"TP_CPLD1_PL1B_L_GPLLC_FB";
25"RST_CPU0_LVC3_R1_N";
26"RST_RSMRST_R_N";
27"PWRGD_PVSA_CPU1";
28"FM_ADR_MODE_SEL";
29"FM_CPU0_RC_EN";
30"TP_CPLD1_PB5A_CSSPIN";
31"PWRGD_PVCCMCP_CPU0";
32"PWRGD_PVCCIOMCP_CPU1";
33"FM_DIS_ADR_DLY";
34"FM_BMC_CPLD_MP_RST_N";
35"PWRGD_PVCCIOMCP_CPU0";
36"PWRGD_PVTT_CPU1";
37"FM_PVCCIOMCP_CPU1_EN";
38"FM_PVCCIO_CPU0_EN";
39"PWRGD_PVPP_ABC";
40"FM_PVCCIO_CPU1_EN";
41"FM_CPLD_USB_P0_EN_N";
42"FM_CPU0_PROC_ID1";
43"FM_CPU0_PKGID1";
44"FM_CPU0_FIVR_FAULT_LVT3_N";
45"PWRGD_P3V3";
46"FM_SLPS3_N";
47"FM_PVCCMCP_CPU0_EN";
48"FM_MP_PS_FAIL_N";
49"PWRGD_P5V";
50"FM_CPU0_PKGID2";
51"RST_RSMRST_N";
52"FM_CPU1_RC_EN";
53"RST_PCIE_M2_DEV_N";
54"PWRGD_PVPP_DEF";
55"PWRGD_PVCCIO_CPU0";
56"PWRGD_PVNN_P1V05_PCH";
57"FM_CPLD_DBG_PWR_EN_N";
58"FM_156M_CPU1_BRD_OSC_EN";
59"FM_IE_DISABLE_N";
60"TP_CPLD1_PB8B_SO_SPISO";
61"TP_CPLD1_PB8A_MCLK_CCLK";
62"RST_CPU0_LVC3_N";
63"FM_UARTSW_LSB_N";
64"FM_156M_CPU0_BRD_OSC_EN";
65"TP_CPLD1_PB25B_SI_SISPI";
66"FM_CPLD_BMC_PWRDN_N";
67"FM_DB1200ZL_BCLKS_EN_N";
68"FM_CPU1_SKTOCC_LVT3_N";
69"FM_CPU0_VRM_OSC_EN";
70"FM_CPU1_PKGID0";
71"PWRGD_DRAMPWRGD";
72"FM_CPU_CATERR_LVT3_N";
73"XDP_PWRGD_RST_N";
74"PWRGD_CPU1_LVC3";
75"XDP_SYSPWROK";
76"RST_CD_CPU1_POR_N";
77"FM_SOL_UART_CH_SEL";
78"TP_CPLD1_PB16B_PCLKC2_1";
79"FM_PVCCMCP_CPU1_EN";
80"FM_CPLD_UART_CH_LOCK_N";
81"RST_CPU0_LVC3_R1_N";
82"RST_CPU1_LVC3_R1_N";
83"FM_CPU1_PKGID2";
84"RST_PCIE_CPU_DEV2_N";
85"RST_PCIE_CPU_DEV3_N";
86"UART_BMC_RXD5";
87"FM_CPU_MSMI_LVT3_N";
88"FM_CPU1_PKGID1";
89"FM_UART_ALERT_N";
90"FM_BMC_CPLD_GPO";
91"SP1_BMC_HOST_UART_TX";
92"UART_BMC_TXD5";
93"SP1_BMC_HOST_UART_RX";
94"FM_PVCCIOMCP_CPU0_EN";
95"SGPIO_BMC_DOUT";
96"TP_CPLD1_PL7D_PCLKT4_0";
97"SGPIO_BMC_CLK";
98"PWRGD_PVSA_CPU0";
99"TP_CPLD1_PL11A";
100"SGPIO_BMC_LD_N";
101"PWRGD_CPU0_LVC3";
102"CLK_25M_CPLD";
103"RST_RSMRST_DLY";
104"PWRGD_PVCCIN_CPU0";
105"PWRGD_PVCCMCP_CPU1";
106"RST_PCIE_RISER1_PERST_N";
107"PWRGD_PVCCIN_CPU1";
108"PWRGD_PVPP_KLM";
109"PWRGD_PVPP_GHJ";
110"RST_CD_CPU0_POR_N";
%"RES"
"1","(-4150,5200)","0","mstr_discrete","I116";
;
CDS_SEC"1"
LOCATION"R3P34"
PART_NUMBER"G21497-005"
VALUE"0.0"
TOLERANCE"5%"
PACK_TYPE"0402"
MATERIAL"CHIP"
WATTAGE"1/16W"
SEC_TYPE"0402"
CDS_LIB"mstr_discrete"
BOM_COST"CPLD"
SEC"1"
CDS_LOCATION"R3P34"
ROOM"CPLD";
"B"
$PN"2"62;
"A"
$PN"1"25;
%"RES"
"1","(-4150,5000)","0","mstr_discrete","I117";
;
CDS_SEC"1"
WATTAGE"1/16W"
LOCATION"R3P35"
PART_NUMBER"G21497-005"
TOLERANCE"5%"
PACK_TYPE"0402"
MATERIAL"CHIP"
VALUE"0.0"
SEC_TYPE"0402"
BOM_COST"CPLD"
CDS_LIB"mstr_discrete"
SEC"1"
CDS_LOCATION"R3P35"
ROOM"CPLD";
"B"
$PN"2"6;
"A"
$PN"1"14;
%"LCMXO2_A"
"4","(-1950,2950)","0","mstr_memory","I179";
;
CDS_SEC"1"
PART_NUMBER"H63395-001"
MATERIAL"IC"
LOCATION"U8D7"
PACK_TYPE"256BGA"
ROOM"CPLD"
SEC_TYPE"256BGA"
SEC"1"
CDS_LIB"mstr_memory"
CDS_LMAN_SYM_OUTLINE"-550,1750,550,-1750"
CDS_LOCATION"U8D7"
BOM_COST"CPLD";
"PL7C_PCLKT4_0"
$PN"J1"97;
"PB19A"
$PN"P10"76;
"PB18D"
$PN"L10"77;
"PB18C"
$PN"M9"80;
"PL5D"
$PN"H6"45;
"PB3A"
$PN"P4"52;
"PB3B"
$PN"T4"27;
"PB3C"
$PN"T2"28;
"PB3D"
$PN"R3"29;
"PB5A_CSSPIN"
$PN"R5"30;
"PB5B"
$PN"P5"31;
"PB6A"
$PN"T5"32;
"PB6B"
$PN"R6"53;
"PB6C"
$PN"T3"33;
"PB6D"
$PN"R4"34;
"PB8A_MCLK_CCLK"
$PN"P6"61;
"PB8B_SO_SPISO"
$PN"T6"60;
"PB8C"
$PN"N6"35;
"PB8D"
$PN"L7"3;
"PB9A"
$PN"R7"36;
"PB9B"
$PN"P7"37;
"PB9C"
$PN"M7"38;
"PB9D"
$PN"N7"39;
"PB11A_PCLKT2_0"
$PN"T7"40;
"PB11B_PCLKC2_0"
$PN"R8"41;
"PB11C"
$PN"M6"54;
"PB11D"
$PN"L8"55;
"PB12A"
$PN"P8"56;
"PB12B"
$PN"T8"57;
"PB12C"
$PN"N8"58;
"PB12D"
$PN"L9"59;
"PB16A_PCLKT2_1"
$PN"T9"8;
"PB16B_PCLKC2_1"
$PN"P9"78;
"PB16C"
$PN"M8"79;
"PB16D"
$PN"N9"66;
"PB18A"
$PN"R9"63;
"PB18B"
$PN"T10"64;
"PB19B"
$PN"R10"81;
"PB19C"
$PN"N10"82;
"PB19D"
$PN"M11"73;
"PB21A"
$PN"T11"83;
"PB21B"
$PN"P11"10;
"PB21C"
$PN"M10"74;
"PB21D"
$PN"N11"75;
"PB22A"
$PN"R11"67;
"PB22B"
$PN"T12"68;
"PB22C"
$PN"R13"69;
"PB22D"
$PN"T14"4;
"PB24A"
$PN"P12"88;
"PB24B"
$PN"T13"87;
"PB25A_SN"
$PN"R12"70;
"PB25B_SI_SISPI"
$PN"P13"65;
"PB25C"
$PN"T15"71;
"PB25D"
$PN"R14"72;
"PL1A_L_GPLLT_FB"
$PN"D3"9;
"PL1B_L_GPLLC_FB"
$PN"D1"24;
"PL1C"
$PN"B1"12;
"PL1D"
$PN"C2"23;
"PL2A_L_GPLLT_IN"
$PN"E2"22;
"PL2B_L_GPLLC_IN"
$PN"E3"17;
"PL2C"
$PN"C1"18;
"PL2D"
$PN"D2"19;
"PL3A_PCLKT5_0"
$PN"E1"7;
"PL3B_PCLKC5_0"
$PN"F2"2;
"PL3C"
$PN"F4"16;
"PL3D"
$PN"G6"13;
"PL4A"
$PN"F3"42;
"PL4B"
$PN"F1"11;
"PL4C"
$PN"G5"20;
"PL4D"
$PN"G4"21;
"PL5A"
$PN"G2"50;
"PL5B"
$PN"G3"43;
"PL5C"
$PN"F5"44;
"PL6A"
$PN"G1"46;
"PL6B"
$PN"H2"47;
"PL6C"
$PN"H4"48;
"PL6D"
$PN"J6"49;
"PL7A"
$PN"H3"84;
"PL7B"
$PN"H1"85;
"PL7D_PCLKC4_0"
$PN"J3"96;
"PL9A"
$PN"J2"95;
"PL9B"
$PN"K1"94;
"PL9C"
$PN"H5"0;
"PL9D"
$PN"J4"0;
"PL10A"
$PN"K3"93;
"PL10B"
$PN"K2"91;
"PL10C"
$PN"J5"86;
"PL10D"
$PN"K6"92;
"PL11A"
$PN"L1"98;
"PL11B"
$PN"L3"99;
"PL11C"
$PN"K4"100;
"PL11D"
$PN"L5"101;
"PL12A_PCLKT3_0"
$PN"L2"102;
"PL12B_PCLKC3_0"
$PN"M1"103;
"PL12C"
$PN"K5"104;
"PL12D"
$PN"L4"105;
"PL13A"
$PN"M3"106;
"PL13B"
$PN"N1"107;
"PL13C"
$PN"N2"108;
"PL13D"
$PN"P1"5;
"PL14A"
$PN"M2"109;
"PL14B"
$PN"N3"110;
"PL14C"
$PN"R1"90;
"PL14D"
$PN"P2"89;
%"RES"
"1","(-1350,5200)","0","mstr_discrete","I338";
;
MATERIAL"CHIP"
LOCATION"R2R2"
VALUE"33.2"
PACK_TYPE"0402"
PART_NUMBER"G21796-074"
TOLERANCE"1%"
WATTAGE"1/16W"
CDS_LIB"mstr_discrete"
BOM_COST"CPLD"
CDS_SEC"1"
$SEC"1"
CDS_LOCATION"R2R2"
ROOM"CPLD";
"B"
$PN"2"51;
"A"
$PN"1"26;
%"RES"
"2","(-1800,5000)","0","mstr_discrete","I349";
;
CDS_SEC"1"
PACK_TYPE"0402"
MATERIAL"EMPTY"
WATTAGE"1/16W"
TOLERANCE"1%"
LOCATION"R1W26"
VALUE"10.0K"
PART_NUMBER"G21796-016"
CDS_LOCATION"R1W26"
ROOM"DB1200ZL"
SEC"1"
SEC_TYPE"0402"
BOM_COST"SYS_CLOCK"
CDS_LIB"mstr_discrete";
"A"
$PN"1"26;
"B"
$PN"2"1;
%"GND"
"1","(-1800,4800)","0","mstr_symbols","I350";
;
ROOM"DB1200ZL"
BOM_COST"SYS_CLOCK"
VOLTAGE"0.0V"
CDS_LIB"mstr_symbols"
SIZE"1B"
BODY_TYPE"PLUMBING"
HDL_POWER"GND";
"A\NAC"1;
%"RES"
"1","(-3300,3900)","0","mstr_discrete","I351";
;
PART_NUMBER"G21497-005"
MATERIAL"CHIP"
WATTAGE"1/16W"
LOCATION"R1W27"
VALUE"0.0"
TOLERANCE"5%"
SEC_TYPE"0402"
CDS_LIB"mstr_discrete"
SEC"1"
ROOM"BMC"
BOM_COST"SM_CONTROLLER"
PACK_TYPE"0402"
CDS_SEC"1"
CDS_LOCATION"R1W27";
"B"
$PN"2"13;
"A"
$PN"1"15;
END.
